FILE_TYPE=LIBRARY_PARTS;
TIME=' Created/Modified on Fri May 04 13:31:09 2001' ;
primitive 'PNP';
  pin
    'B':
      PIN_NUMBER='(1)';
      PINUSE='UNSPEC';
      NO_LOAD_CHECK='BOTH';
      NO_IO_CHECK='BOTH';
      ALLOW_CONNECT='TRUE';
    'C':
      PIN_NUMBER='(3)';
      PINUSE='UNSPEC';
      NO_LOAD_CHECK='BOTH';
      NO_IO_CHECK='BOTH';
      ALLOW_CONNECT='TRUE';
    'E':
      PIN_NUMBER='(2)';
      PINUSE='UNSPEC';
      NO_LOAD_CHECK='BOTH';
      NO_IO_CHECK='BOTH';
      ALLOW_CONNECT='TRUE';
  end_pin;
  body
    PART_NAME='PNP';
    PHYS_DES_PREFIX='Q';
  end_body;
end_primitive;
primitive 'PNP_SOT369';
  pin
    'B':
      PIN_NUMBER='(1)';
      PINUSE='UNSPEC';
      NO_LOAD_CHECK='BOTH';
      NO_IO_CHECK='BOTH';
      ALLOW_CONNECT='TRUE';
    'C':
      PIN_NUMBER='(4)';
      PINUSE='UNSPEC';
      NO_LOAD_CHECK='BOTH';
      NO_IO_CHECK='BOTH';
      ALLOW_CONNECT='TRUE';
    'E':
      PIN_NUMBER='(3)';
      PINUSE='UNSPEC';
      NO_LOAD_CHECK='BOTH';
      NO_IO_CHECK='BOTH';
      ALLOW_CONNECT='TRUE';
  end_pin;
  body
    PART_NAME='PNP';
    PHYS_DES_PREFIX='Q';
  end_body;
end_primitive;
END.
